(kicad_pcb
	(version 20241229)
	(generator "pcbnew")
	(generator_version "9.0")
	(general
		(thickness 1.711)
		(legacy_teardrops no)
	)
	(paper "A4")
	(title_block
		(title "Antmicro Baseboard for Jetson AGX Thor")
		(date "2026-02-18")
		(rev "1.1.0")
		(company "Antmicro Ltd")
		(comment 1 "www.antmicro.com")
		(comment 9 "footprints 33-37 of 1170")
	)
	(layers
		(0 "F.Cu" signal)
		(4 "In1.Cu" signal)
		(6 "In2.Cu" signal)
		(8 "In3.Cu" signal)
		(10 "In4.Cu" jumper)
		(12 "In5.Cu" signal)
		(14 "In6.Cu" signal)
		(16 "In7.Cu" signal)
		(18 "In8.Cu" signal)
		(2 "B.Cu" signal)
		(9 "F.Adhes" user "F.Adhesive")
		(11 "B.Adhes" user "B.Adhesive")
		(13 "F.Paste" user)
		(15 "B.Paste" user)
		(5 "F.SilkS" user "F.Silkscreen")
		(7 "B.SilkS" user "B.Silkscreen")
		(1 "F.Mask" user)
		(3 "B.Mask" user)
		(17 "Dwgs.User" user "User.Drawings")
		(19 "Cmts.User" user "User.Comments")
		(21 "Eco1.User" user "User.Eco1")
		(23 "Eco2.User" user "User.Eco2")
		(25 "Edge.Cuts" user)
		(27 "Margin" user)
		(31 "F.CrtYd" user "F.Courtyard")
		(29 "B.CrtYd" user "B.Courtyard")
		(35 "F.Fab" user)
		(33 "B.Fab" user)
	)
	(footprint "antmicro-footprints:R_0402_1005Metric"
		(layer "F.Cu")
		(at 183.25 139)
		(descr "Resistor SMD 0402")
		(tags "resistor SMD 0402")
		(property "Reference" "R18"
			(at -0.35 -1.6 0)
			(layer "F.SilkS")
			(effects
				(font
					(size 0.7 0.7)
					(thickness 0.15)
				)
				(justify left bottom)
			)
		)
		(property "Value" "R_10k_0402"
			(at -1.011843 1.772047 0)
			(layer "F.Fab")
			(effects
				(font
					(size 0.7 0.7)
					(thickness 0.15)
				)
				(justify left bottom)
			)
		)
		(property "Datasheet" "https://www.bourns.com/docs/product-datasheets/cr.pdf"
			(at 0 0 0)
			(layer "F.Fab")
			(hide yes)
			(effects
				(font
					(size 1.27 1.27)
					(thickness 0.15)
				)
			)
		)
		(property "Description" "SMD Chip Resistor, 10 kohm, ± 1%, 62.5 mW, 0402 [1005 Metric], Thick Film, General Purpose"
			(at 0 0 0)
			(layer "F.Fab")
			(hide yes)
			(effects
				(font
					(size 1.27 1.27)
					(thickness 0.15)
				)
			)
		)
		(property "MPN" "CR0402-FX-1002GLF"
			(at 0 0 0)
			(unlocked yes)
			(layer "F.Fab")
			(hide yes)
			(effects
				(font
					(size 1 1)
					(thickness 0.15)
				)
			)
		)
		(property "Manufacturer" "Bourns"
			(at 0 0 0)
			(unlocked yes)
			(layer "F.Fab")
			(hide yes)
			(effects
				(font
					(size 1 1)
					(thickness 0.15)
				)
			)
		)
		(property "License" "Apache-2.0"
			(at 0 0 0)
			(unlocked yes)
			(layer "F.Fab")
			(hide yes)
			(effects
				(font
					(size 1 1)
					(thickness 0.15)
				)
			)
		)
		(property "Author" "Antmicro"
			(at 0 0 0)
			(unlocked yes)
			(layer "F.Fab")
			(hide yes)
			(effects
				(font
					(size 1 1)
					(thickness 0.15)
				)
			)
		)
		(property "Val" "10k"
			(at 0 0 0)
			(unlocked yes)
			(layer "F.Fab")
			(hide yes)
			(effects
				(font
					(size 1 1)
					(thickness 0.15)
				)
			)
		)
		(property "Tolerance" "1%"
			(at 0 0 0)
			(unlocked yes)
			(layer "F.Fab")
			(hide yes)
			(effects
				(font
					(size 1 1)
					(thickness 0.15)
				)
			)
		)
		(sheetname "/DCDC/")
		(sheetfile "dcdc.kicad_sch")
		(attr smd)
		(fp_rect
			(start -0.925 -0.47)
			(end 0.925 0.47)
			(stroke
				(width 0.05)
				(type default)
			)
			(fill no)
			(layer "F.CrtYd")
		)
		(fp_rect
			(start -0.5 -0.25)
			(end 0.5 0.25)
			(stroke
				(width 0.15)
				(type solid)
			)
			(fill no)
			(layer "F.Fab")
		)
		(fp_text user "License: Apache-2.0"
			(at -0.95 5.169 0)
			(layer "F.Fab")
			(effects
				(font
					(size 0.7 0.7)
					(thickness 0.15)
				)
				(justify left bottom)
			)
		)
		(fp_text user "${REFERENCE}"
			(at -0.95 3.168 0)
			(layer "F.Fab")
			(effects
				(font
					(size 0.7 0.7)
					(thickness 0.15)
				)
				(justify left bottom)
			)
		)
		(fp_text user "Author: Antmicro"
			(at -0.95 4.169 0)
			(layer "F.Fab")
			(effects
				(font
					(size 0.7 0.7)
					(thickness 0.15)
				)
				(justify left bottom)
			)
		)
		(pad "1" smd roundrect
			(at -0.48 0)
			(size 0.59 0.64)
			(layers "F.Cu" "F.Mask" "F.Paste")
			(roundrect_rratio 0.25)
			(net 1 "GND")
			(pintype "passive")
		)
		(pad "2" smd roundrect
			(at 0.48 0)
			(size 0.59 0.64)
			(layers "F.Cu" "F.Mask" "F.Paste")
			(roundrect_rratio 0.25)
			(net 1206 "/DCDC/12V_FB")
			(pintype "passive")
		)
	)
	(footprint "antmicro-footprints:C_0402_1005Metric"
		(layer "F.Cu")
		(at 205.9 134.8 90)
		(descr "Capacitor SMD 0402")
		(tags "capacitor SMD 0402")
		(property "Reference" "C253"
			(at -1.59 13.89 90)
			(layer "F.SilkS")
			(effects
				(font
					(size 0.7 0.7)
					(thickness 0.15)
				)
				(justify left bottom)
			)
		)
		(property "Value" "C_100n_0402"
			(at -1.022927 2.155213 90)
			(layer "F.Fab")
			(effects
				(font
					(size 0.7 0.7)
					(thickness 0.15)
				)
				(justify left bottom)
			)
		)
		(property "Datasheet" "https://www.murata.com/products/productdetail?partno=GRM155R61H104KE14%23"
			(at 0 0 90)
			(layer "F.Fab")
			(hide yes)
			(effects
				(font
					(size 1.27 1.27)
					(thickness 0.15)
				)
			)
		)
		(property "Description" "SMD Multilayer Ceramic Capacitor, 0.1 µF, 50 V, 0402 [1005 Metric], ± 10%, X5R, GRM Series"
			(at 0 0 90)
			(layer "F.Fab")
			(hide yes)
			(effects
				(font
					(size 1.27 1.27)
					(thickness 0.15)
				)
			)
		)
		(property "Manufacturer" "Murata"
			(at 0 0 90)
			(unlocked yes)
			(layer "F.Fab")
			(hide yes)
			(effects
				(font
					(size 1 1)
					(thickness 0.15)
				)
			)
		)
		(property "MPN" "GRM155R61H104KE14D"
			(at 0 0 90)
			(unlocked yes)
			(layer "F.Fab")
			(hide yes)
			(effects
				(font
					(size 1 1)
					(thickness 0.15)
				)
			)
		)
		(property "Val" "100n"
			(at 0 0 90)
			(unlocked yes)
			(layer "F.Fab")
			(hide yes)
			(effects
				(font
					(size 1 1)
					(thickness 0.15)
				)
			)
		)
		(property "License" "Apache-2.0"
			(at 0 0 90)
			(unlocked yes)
			(layer "F.Fab")
			(hide yes)
			(effects
				(font
					(size 1 1)
					(thickness 0.15)
				)
			)
		)
		(property "Author" "Antmicro"
			(at 0 0 90)
			(unlocked yes)
			(layer "F.Fab")
			(hide yes)
			(effects
				(font
					(size 1 1)
					(thickness 0.15)
				)
			)
		)
		(property "Voltage" "50V"
			(at 0 0 90)
			(unlocked yes)
			(layer "F.Fab")
			(hide yes)
			(effects
				(font
					(size 1 1)
					(thickness 0.15)
				)
			)
		)
		(property "Dielectric" "X5R"
			(at 0 0 90)
			(unlocked yes)
			(layer "F.Fab")
			(hide yes)
			(effects
				(font
					(size 1 1)
					(thickness 0.15)
				)
			)
		)
		(sheetname "/USB Hub/")
		(sheetfile "usb_hub.kicad_sch")
		(attr smd)
		(fp_rect
			(start -0.925 -0.47)
			(end 0.925 0.47)
			(stroke
				(width 0.05)
				(type default)
			)
			(fill no)
			(layer "F.CrtYd")
		)
		(fp_line
			(start 0.504 -0.25)
			(end 0.504 0.248)
			(stroke
				(width 0.15)
				(type solid)
			)
			(layer "F.Fab")
		)
		(fp_line
			(start -0.494 -0.25)
			(end 0.504 -0.25)
			(stroke
				(width 0.15)
				(type solid)
			)
			(layer "F.Fab")
		)
		(fp_line
			(start 0.504 0.248)
			(end -0.494 0.248)
			(stroke
				(width 0.15)
				(type solid)
			)
			(layer "F.Fab")
		)
		(fp_line
			(start -0.494 0.248)
			(end -0.494 -0.25)
			(stroke
				(width 0.15)
				(type solid)
			)
			(layer "F.Fab")
		)
		(fp_text user "${REFERENCE}"
			(at -0.939 4.599 90)
			(layer "F.Fab")
			(effects
				(font
					(size 0.7 0.7)
					(thickness 0.15)
				)
				(justify left bottom)
			)
		)
		(fp_text user "License: Apache-2.0"
			(at -0.939 5.799 90)
			(layer "F.Fab")
			(effects
				(font
					(size 0.7 0.7)
					(thickness 0.15)
				)
				(justify left bottom)
			)
		)
		(fp_text user "Author: Antmicro"
			(at -0.939 3.399 90)
			(layer "F.Fab")
			(effects
				(font
					(size 0.7 0.7)
					(thickness 0.15)
				)
				(justify left bottom)
			)
		)
		(pad "1" smd roundrect
			(at -0.48 0 90)
			(size 0.59 0.64)
			(layers "F.Cu" "F.Mask" "F.Paste")
			(roundrect_rratio 0.25)
			(net 770 "/SoM_IO2/USBSS2.RX+")
			(pintype "passive")
		)
		(pad "2" smd roundrect
			(at 0.48 0 90)
			(size 0.59 0.64)
			(layers "F.Cu" "F.Mask" "F.Paste")
			(roundrect_rratio 0.25)
			(net 1132 "/USB Hub/USBSS_TX_P")
			(pintype "passive")
		)
	)
	(footprint "antmicro-footprints:C_0402_1005Metric"
		(layer "F.Cu")
		(at 94 60.5 180)
		(descr "Capacitor SMD 0402")
		(tags "capacitor SMD 0402")
		(property "Reference" "C251"
			(at -9.75 -0.78 0)
			(layer "F.SilkS")
			(effects
				(font
					(size 0.7 0.7)
					(thickness 0.15)
				)
				(justify right top)
			)
		)
		(property "Value" "C_1u_25V_0402"
			(at -1.022927 2.155213 0)
			(layer "F.Fab")
			(effects
				(font
					(size 0.7 0.7)
					(thickness 0.15)
				)
				(justify right top)
			)
		)
		(property "Datasheet" "https://www.murata.com/products/productdetail?partno=GRM155R61E105KE11%23"
			(at 0 0 0)
			(layer "F.Fab")
			(hide yes)
			(effects
				(font
					(size 1.27 1.27)
					(thickness 0.15)
				)
			)
		)
		(property "Description" "SMD Multilayer Ceramic Capacitor, 1 µF, 25 V, 0402 [1005 Metric], ± 10%, X5R, GRM Series"
			(at 0 0 0)
			(layer "F.Fab")
			(hide yes)
			(effects
				(font
					(size 1.27 1.27)
					(thickness 0.15)
				)
			)
		)
		(property "MPN" "GRM155R61E105KE11J"
			(at 0 0 180)
			(unlocked yes)
			(layer "F.Fab")
			(hide yes)
			(effects
				(font
					(size 1 1)
					(thickness 0.15)
				)
			)
		)
		(property "Manufacturer" "Murata"
			(at 0 0 180)
			(unlocked yes)
			(layer "F.Fab")
			(hide yes)
			(effects
				(font
					(size 1 1)
					(thickness 0.15)
				)
			)
		)
		(property "License" "Apache-2.0"
			(at 0 0 180)
			(unlocked yes)
			(layer "F.Fab")
			(hide yes)
			(effects
				(font
					(size 1 1)
					(thickness 0.15)
				)
			)
		)
		(property "Author" "Antmicro"
			(at 0 0 180)
			(unlocked yes)
			(layer "F.Fab")
			(hide yes)
			(effects
				(font
					(size 1 1)
					(thickness 0.15)
				)
			)
		)
		(property "Val" "1u"
			(at 0 0 180)
			(unlocked yes)
			(layer "F.Fab")
			(hide yes)
			(effects
				(font
					(size 1 1)
					(thickness 0.15)
				)
			)
		)
		(property "Voltage" "25V"
			(at 0 0 180)
			(unlocked yes)
			(layer "F.Fab")
			(hide yes)
			(effects
				(font
					(size 1 1)
					(thickness 0.15)
				)
			)
		)
		(property "Dielectric" "X5R"
			(at 0 0 180)
			(unlocked yes)
			(layer "F.Fab")
			(hide yes)
			(effects
				(font
					(size 1 1)
					(thickness 0.15)
				)
			)
		)
		(sheetname "/SoM_Power/")
		(sheetfile "som_power.kicad_sch")
		(attr smd)
		(fp_rect
			(start -0.925 -0.47)
			(end 0.925 0.47)
			(stroke
				(width 0.05)
				(type default)
			)
			(fill no)
			(layer "F.CrtYd")
		)
		(fp_line
			(start 0.504 0.248)
			(end -0.494 0.248)
			(stroke
				(width 0.15)
				(type solid)
			)
			(layer "F.Fab")
		)
		(fp_line
			(start 0.504 -0.25)
			(end 0.504 0.248)
			(stroke
				(width 0.15)
				(type solid)
			)
			(layer "F.Fab")
		)
		(fp_line
			(start -0.494 0.248)
			(end -0.494 -0.25)
			(stroke
				(width 0.15)
				(type solid)
			)
			(layer "F.Fab")
		)
		(fp_line
			(start -0.494 -0.25)
			(end 0.504 -0.25)
			(stroke
				(width 0.15)
				(type solid)
			)
			(layer "F.Fab")
		)
		(fp_text user "Author: Antmicro"
			(at -0.939 3.399 0)
			(layer "F.Fab")
			(effects
				(font
					(size 0.7 0.7)
					(thickness 0.15)
				)
				(justify right top)
			)
		)
		(fp_text user "License: Apache-2.0"
			(at -0.939 5.799 0)
			(layer "F.Fab")
			(effects
				(font
					(size 0.7 0.7)
					(thickness 0.15)
				)
				(justify right top)
			)
		)
		(fp_text user "${REFERENCE}"
			(at -0.939 4.599 0)
			(layer "F.Fab")
			(effects
				(font
					(size 0.7 0.7)
					(thickness 0.15)
				)
				(justify right top)
			)
		)
		(pad "1" smd roundrect
			(at -0.48 0 180)
			(size 0.59 0.64)
			(layers "F.Cu" "F.Mask" "F.Paste")
			(roundrect_rratio 0.25)
			(net 524 "Net-(Q22-D)")
			(pintype "passive")
		)
		(pad "2" smd roundrect
			(at 0.48 0 180)
			(size 0.59 0.64)
			(layers "F.Cu" "F.Mask" "F.Paste")
			(roundrect_rratio 0.25)
			(net 610 "/SoM_Power/~{PWR_BTN}")
			(pintype "passive")
		)
	)
	(footprint "antmicro-footprints:C_0402_1005Metric"
		(layer "F.Cu")
		(at 197.215 121.9)
		(descr "Capacitor SMD 0402")
		(tags "capacitor SMD 0402")
		(property "Reference" "C47"
			(at -1.315 -1.8 0)
			(layer "F.SilkS")
			(effects
				(font
					(size 0.7 0.7)
					(thickness 0.15)
				)
				(justify left bottom)
			)
		)
		(property "Value" "C_100n_0402"
			(at -1.022927 2.155213 0)
			(layer "F.Fab")
			(effects
				(font
					(size 0.7 0.7)
					(thickness 0.15)
				)
				(justify left bottom)
			)
		)
		(property "Datasheet" "https://www.murata.com/products/productdetail?partno=GRM155R61H104KE14%23"
			(at 0 0 0)
			(layer "F.Fab")
			(hide yes)
			(effects
				(font
					(size 1.27 1.27)
					(thickness 0.15)
				)
			)
		)
		(property "Description" "SMD Multilayer Ceramic Capacitor, 0.1 µF, 50 V, 0402 [1005 Metric], ± 10%, X5R, GRM Series"
			(at 0 0 0)
			(layer "F.Fab")
			(hide yes)
			(effects
				(font
					(size 1.27 1.27)
					(thickness 0.15)
				)
			)
		)
		(property "MPN" "GRM155R61H104KE14D"
			(at 0 0 0)
			(unlocked yes)
			(layer "F.Fab")
			(hide yes)
			(effects
				(font
					(size 1 1)
					(thickness 0.15)
				)
			)
		)
		(property "Val" "100n"
			(at 0 0 0)
			(unlocked yes)
			(layer "F.Fab")
			(hide yes)
			(effects
				(font
					(size 1 1)
					(thickness 0.15)
				)
			)
		)
		(property "Voltage" "50V"
			(at 0 0 0)
			(unlocked yes)
			(layer "F.Fab")
			(hide yes)
			(effects
				(font
					(size 1 1)
					(thickness 0.15)
				)
			)
		)
		(property "Dielectric" "X5R"
			(at 0 0 0)
			(unlocked yes)
			(layer "F.Fab")
			(hide yes)
			(effects
				(font
					(size 1 1)
					(thickness 0.15)
				)
			)
		)
		(property "Manufacturer" "Murata"
			(at 0 0 0)
			(unlocked yes)
			(layer "F.Fab")
			(hide yes)
			(effects
				(font
					(size 1 1)
					(thickness 0.15)
				)
			)
		)
		(property "License" "Apache-2.0"
			(at 0 0 0)
			(unlocked yes)
			(layer "F.Fab")
			(hide yes)
			(effects
				(font
					(size 1 1)
					(thickness 0.15)
				)
			)
		)
		(property "Author" "Antmicro"
			(at 0 0 0)
			(unlocked yes)
			(layer "F.Fab")
			(hide yes)
			(effects
				(font
					(size 1 1)
					(thickness 0.15)
				)
			)
		)
		(sheetname "/USB Hub/")
		(sheetfile "usb_hub.kicad_sch")
		(attr smd)
		(fp_rect
			(start -0.925 -0.47)
			(end 0.925 0.47)
			(stroke
				(width 0.05)
				(type default)
			)
			(fill no)
			(layer "F.CrtYd")
		)
		(fp_line
			(start -0.494 -0.25)
			(end 0.504 -0.25)
			(stroke
				(width 0.15)
				(type solid)
			)
			(layer "F.Fab")
		)
		(fp_line
			(start -0.494 0.248)
			(end -0.494 -0.25)
			(stroke
				(width 0.15)
				(type solid)
			)
			(layer "F.Fab")
		)
		(fp_line
			(start 0.504 -0.25)
			(end 0.504 0.248)
			(stroke
				(width 0.15)
				(type solid)
			)
			(layer "F.Fab")
		)
		(fp_line
			(start 0.504 0.248)
			(end -0.494 0.248)
			(stroke
				(width 0.15)
				(type solid)
			)
			(layer "F.Fab")
		)
		(fp_text user "${REFERENCE}"
			(at -0.939 4.599 0)
			(layer "F.Fab")
			(effects
				(font
					(size 0.7 0.7)
					(thickness 0.15)
				)
				(justify left bottom)
			)
		)
		(fp_text user "Author: Antmicro"
			(at -0.939 3.399 0)
			(layer "F.Fab")
			(effects
				(font
					(size 0.7 0.7)
					(thickness 0.15)
				)
				(justify left bottom)
			)
		)
		(fp_text user "License: Apache-2.0"
			(at -0.939 5.799 0)
			(layer "F.Fab")
			(effects
				(font
					(size 0.7 0.7)
					(thickness 0.15)
				)
				(justify left bottom)
			)
		)
		(pad "1" smd roundrect
			(at -0.48 0)
			(size 0.59 0.64)
			(layers "F.Cu" "F.Mask" "F.Paste")
			(roundrect_rratio 0.25)
			(net 1 "GND")
			(pintype "passive")
		)
		(pad "2" smd roundrect
			(at 0.48 0)
			(size 0.59 0.64)
			(layers "F.Cu" "F.Mask" "F.Paste")
			(roundrect_rratio 0.25)
			(net 2 "+3V3")
			(pintype "passive")
		)
	)
	(footprint "antmicro-footprints:R_0402_1005Metric"
		(layer "F.Cu")
		(at 156.72 111.2 180)
		(descr "Resistor SMD 0402")
		(tags "resistor SMD 0402")
		(property "Reference" "R377"
			(at -3.68 0.4 0)
			(layer "F.SilkS")
			(effects
				(font
					(size 0.7 0.7)
					(thickness 0.15)
				)
				(justify right top)
			)
		)
		(property "Value" "R_2k2_0402"
			(at -1.011843 1.772047 0)
			(layer "F.Fab")
			(effects
				(font
					(size 0.7 0.7)
					(thickness 0.15)
				)
				(justify right top)
			)
		)
		(property "Datasheet" "https://www.bourns.com/docs/product-datasheets/cr.pdf"
			(at 0 0 0)
			(layer "F.Fab")
			(hide yes)
			(effects
				(font
					(size 1.27 1.27)
					(thickness 0.15)
				)
			)
		)
		(property "Description" "SMD Chip Resistor, 2.2 kohm, ± 1%, 62.5 mW, 0402 [1005 Metric], Thick Film, General Purpose"
			(at 0 0 0)
			(layer "F.Fab")
			(hide yes)
			(effects
				(font
					(size 1.27 1.27)
					(thickness 0.15)
				)
			)
		)
		(property "MPN" "CR0402-FX-2201GLF"
			(at 0 0 180)
			(unlocked yes)
			(layer "F.Fab")
			(hide yes)
			(effects
				(font
					(size 1 1)
					(thickness 0.15)
				)
			)
		)
		(property "Manufacturer" "Bourns"
			(at 0 0 180)
			(unlocked yes)
			(layer "F.Fab")
			(hide yes)
			(effects
				(font
					(size 1 1)
					(thickness 0.15)
				)
			)
		)
		(property "License" "Apache-2.0"
			(at 0 0 180)
			(unlocked yes)
			(layer "F.Fab")
			(hide yes)
			(effects
				(font
					(size 1 1)
					(thickness 0.15)
				)
			)
		)
		(property "Author" "Antmicro"
			(at 0 0 180)
			(unlocked yes)
			(layer "F.Fab")
			(hide yes)
			(effects
				(font
					(size 1 1)
					(thickness 0.15)
				)
			)
		)
		(property "Val" "2k2"
			(at 0 0 180)
			(unlocked yes)
			(layer "F.Fab")
			(hide yes)
			(effects
				(font
					(size 1 1)
					(thickness 0.15)
				)
			)
		)
		(property "Tolerance" "1%"
			(at 0 0 180)
			(unlocked yes)
			(layer "F.Fab")
			(hide yes)
			(effects
				(font
					(size 1 1)
					(thickness 0.15)
				)
			)
		)
		(sheetname "/SoM_IO/")
		(sheetfile "som_io.kicad_sch")
		(attr smd)
		(fp_rect
			(start -0.925 -0.47)
			(end 0.925 0.47)
			(stroke
				(width 0.05)
				(type default)
			)
			(fill no)
			(layer "F.CrtYd")
		)
		(fp_rect
			(start -0.5 -0.25)
			(end 0.5 0.25)
			(stroke
				(width 0.15)
				(type solid)
			)
			(fill no)
			(layer "F.Fab")
		)
		(fp_text user "${REFERENCE}"
			(at -0.95 3.168 0)
			(layer "F.Fab")
			(effects
				(font
					(size 0.7 0.7)
					(thickness 0.15)
				)
				(justify right top)
			)
		)
		(fp_text user "Author: Antmicro"
			(at -0.95 4.169 0)
			(layer "F.Fab")
			(effects
				(font
					(size 0.7 0.7)
					(thickness 0.15)
				)
				(justify right top)
			)
		)
		(fp_text user "License: Apache-2.0"
			(at -0.95 5.169 0)
			(layer "F.Fab")
			(effects
				(font
					(size 0.7 0.7)
					(thickness 0.15)
				)
				(justify right top)
			)
		)
		(pad "1" smd roundrect
			(at -0.48 0 180)
			(size 0.59 0.64)
			(layers "F.Cu" "F.Mask" "F.Paste")
			(roundrect_rratio 0.25)
			(net 2 "+3V3")
			(pintype "passive")
		)
		(pad "2" smd roundrect
			(at 0.48 0 180)
			(size 0.59 0.64)
			(layers "F.Cu" "F.Mask" "F.Paste")
			(roundrect_rratio 0.25)
			(net 853 "/I2C_{SYS}.SCL")
			(pintype "passive")
		)
	)
)
